(kicad_pcb
	(version 20260206)
	(generator "pcbnew")
	(generator_version "10.0")
	(general
		(thickness 1.6)
		(legacy_teardrops no)
	)
	(paper "A4")
	(title_block
		(title "04192023_DAF0TMB3IC0_F0TG_MB_C_brd_V02_OCP.brd")
		(comment 1 "Grand Teton / footprints 2649-2654 of 8354")
	)
	(layers
		(0 "F.Cu" signal "TOP")
		(4 "In1.Cu" signal "GND")
		(6 "In2.Cu" signal "IN1")
		(8 "In3.Cu" signal "GND1")
		(10 "In4.Cu" signal "IN2")
		(12 "In5.Cu" signal "GND2")
		(14 "In6.Cu" signal "IN3")
		(16 "In7.Cu" signal "GND3")
		(18 "In8.Cu" signal "VCC")
		(20 "In9.Cu" signal "VCC1")
		(22 "In10.Cu" signal "GND4")
		(24 "In11.Cu" signal "IN4")
		(26 "In12.Cu" signal "GND5")
		(28 "In13.Cu" signal "IN5")
		(30 "In14.Cu" signal "GND6")
		(32 "In15.Cu" signal "IN6")
		(34 "In16.Cu" signal "GND7")
		(2 "B.Cu" signal "BOTTOM")
		(9 "F.Adhes" user "F.Adhesive")
		(11 "B.Adhes" user "B.Adhesive")
		(13 "F.Paste" user "Package Geometry/Pastemask Top")
		(15 "B.Paste" user "Package Geometry/Pastemask Bottom")
		(5 "F.SilkS" user "Ref Des/Silkscreen Top")
		(7 "B.SilkS" user "Ref Des/Silkscreen Bottom")
		(1 "F.Mask" user "Board Geometry/Soldermask Top")
		(3 "B.Mask" user "Board Geometry/Soldermask Bottom")
		(17 "Dwgs.User" user "User.Drawings")
		(19 "Cmts.User" user "User.Comments")
		(21 "Eco1.User" user "User.Eco1")
		(23 "Eco2.User" user "User.Eco2")
		(25 "Edge.Cuts" user "Board Geometry/Outline")
		(27 "Margin" user)
		(31 "F.CrtYd" user "Package Geometry/Place Bound Top")
		(29 "B.CrtYd" user "Package Geometry/Place Bound Bottom")
		(35 "F.Fab" user "Ref Des/Assembly Top")
		(33 "B.Fab" user "Ref Des/Assembly Bottom")
	)
	(footprint ""
		(layer "F.Cu")
		(at 451.497192 -20.979638)
		(property "Reference" "PU203"
			(at 2.76479 -1.83896 0)
			(unlocked yes)
			(layer "F.SilkS")
			(effects
				(font
					(size 0.7874 0.5842)
					(thickness 0.1524)
				)
				(justify left)
			)
		)
		(property "Value" ""
			(at 0 0 0)
			(layer "F.Fab")
			(effects
				(font
					(size 1.27 1.27)
				)
			)
		)
		(duplicate_pad_numbers_are_jumpers no)
		(fp_line
			(start -1.774952 -1.039876)
			(end -1.774952 1.039876)
			(stroke
				(width 0.1524)
				(type default)
			)
			(layer "F.SilkS")
		)
		(fp_line
			(start -1.774952 1.039876)
			(end 1.774952 1.039876)
			(stroke
				(width 0.1524)
				(type default)
			)
			(layer "F.SilkS")
		)
		(fp_line
			(start 1.774952 -1.039876)
			(end -1.774952 -1.039876)
			(stroke
				(width 0.1524)
				(type default)
			)
			(layer "F.SilkS")
		)
		(fp_line
			(start 1.774952 1.039876)
			(end 1.774952 -1.039876)
			(stroke
				(width 0.1524)
				(type default)
			)
			(layer "F.SilkS")
		)
		(fp_poly
			(pts
				(xy -0.999998 -1.801876) (xy -0.999998 -1.039876) (xy -1.769872 -1.039876) (xy -1.769872 -0.249936)
				(xy -2.531872 -0.249936) (xy -2.531872 -1.801876)
			)
			(stroke
				(width 0)
				(type default)
			)
			(fill yes)
			(layer "F.SilkS")
		)
		(fp_line
			(start -1.769872 -1.039876)
			(end -1.769872 1.039876)
			(stroke
				(width 0.1)
				(type default)
			)
			(layer "F.Fab")
		)
		(fp_line
			(start -1.769872 1.039876)
			(end 1.769872 1.039876)
			(stroke
				(width 0.1)
				(type default)
			)
			(layer "F.Fab")
		)
		(fp_line
			(start 1.769872 -1.039876)
			(end -1.769872 -1.039876)
			(stroke
				(width 0.1)
				(type default)
			)
			(layer "F.Fab")
		)
		(fp_line
			(start 1.769872 1.039876)
			(end 1.769872 -1.039876)
			(stroke
				(width 0.1)
				(type default)
			)
			(layer "F.Fab")
		)
		(fp_poly
			(pts
				(xy -1.769872 -1.039876) (xy -0.999998 -1.039876) (xy -0.999998 -1.801876) (xy -2.531872 -1.801876)
				(xy -2.531872 -0.249936) (xy -1.769872 -0.249936)
			)
			(stroke
				(width 0)
				(type default)
			)
			(fill yes)
			(layer "F.Fab")
		)
		(pad "A1" smd circle
			(at -1.500124 -0.750062)
			(size 0.2286 0.2286)
			(layers "F.Cu" "F.Mask" "F.Paste")
			(net "P12V_OCP_SENSE_1")
		)
		(pad "A2" smd circle
			(at -0.999998 -0.750062)
			(size 0.2286 0.2286)
			(layers "F.Cu" "F.Mask" "F.Paste")
			(net "P12V_OCP_VCC_1")
		)
		(pad "A3" smd circle
			(at -0.499872 -0.750062)
			(size 0.2286 0.2286)
			(layers "F.Cu" "F.Mask" "F.Paste")
			(net "P12V_AUX")
		)
		(pad "A4" smd circle
			(at 0 -0.750062)
			(size 0.2286 0.2286)
			(layers "F.Cu" "F.Mask" "F.Paste")
			(net "P12V_OCP_SFF")
		)
		(pad "A5" smd circle
			(at 0.499872 -0.750062)
			(size 0.2286 0.2286)
			(layers "F.Cu" "F.Mask" "F.Paste")
			(net "P12V_AUX")
		)
		(pad "A6" smd circle
			(at 0.999998 -0.750062)
			(size 0.2286 0.2286)
			(layers "F.Cu" "F.Mask" "F.Paste")
			(net "P12V_OCP_GATE_1")
		)
		(pad "A7" smd circle
			(at 1.500124 -0.750062)
			(size 0.2286 0.2286)
			(layers "F.Cu" "F.Mask" "F.Paste")
			(net "GND")
		)
		(pad "B1" smd circle
			(at -1.500124 -0.249936)
			(size 0.2286 0.2286)
			(layers "F.Cu" "F.Mask" "F.Paste")
			(net "P12V_OCP_CB_1")
		)
		(pad "B2" smd circle
			(at -0.999998 -0.249936)
			(size 0.2286 0.2286)
			(layers "F.Cu" "F.Mask" "F.Paste")
			(net "GND")
		)
		(pad "B3" smd circle
			(at -0.499872 -0.249936)
			(size 0.2286 0.2286)
			(layers "F.Cu" "F.Mask" "F.Paste")
			(net "P12V_AUX")
		)
		(pad "B4" smd circle
			(at 0 -0.249936)
			(size 0.2286 0.2286)
			(layers "F.Cu" "F.Mask" "F.Paste")
			(net "P12V_OCP_SFF")
		)
		(pad "B5" smd circle
			(at 0.499872 -0.249936)
			(size 0.2286 0.2286)
			(layers "F.Cu" "F.Mask" "F.Paste")
			(net "P12V_AUX")
		)
		(pad "B6" smd circle
			(at 0.999998 -0.249936)
			(size 0.2286 0.2286)
			(layers "F.Cu" "F.Mask" "F.Paste")
			(net "P12V_OCP_SFF")
		)
		(pad "B7" smd circle
			(at 1.500124 -0.249936)
			(size 0.2286 0.2286)
			(layers "F.Cu" "F.Mask" "F.Paste")
			(net "GND")
		)
		(pad "C1" smd circle
			(at -1.500124 0.249936)
			(size 0.2286 0.2286)
			(layers "F.Cu" "F.Mask" "F.Paste")
			(net "GND")
		)
		(pad "C2" smd circle
			(at -0.999998 0.249936)
			(size 0.2286 0.2286)
			(layers "F.Cu" "F.Mask" "F.Paste")
			(net "GND")
		)
		(pad "C3" smd circle
			(at -0.499872 0.249936)
			(size 0.2286 0.2286)
			(layers "F.Cu" "F.Mask" "F.Paste")
			(net "P12V_AUX")
		)
		(pad "C4" smd circle
			(at 0 0.249936)
			(size 0.2286 0.2286)
			(layers "F.Cu" "F.Mask" "F.Paste")
			(net "P12V_OCP_SFF")
		)
		(pad "C5" smd circle
			(at 0.499872 0.249936)
			(size 0.2286 0.2286)
			(layers "F.Cu" "F.Mask" "F.Paste")
			(net "P12V_AUX")
		)
		(pad "C6" smd circle
			(at 0.999998 0.249936)
			(size 0.2286 0.2286)
			(layers "F.Cu" "F.Mask" "F.Paste")
			(net "P12V_OCP_SFF")
		)
		(pad "C7" smd circle
			(at 1.500124 0.249936)
			(size 0.2286 0.2286)
			(layers "F.Cu" "F.Mask" "F.Paste")
			(net "P12V_OCP_FAULT_1")
		)
		(pad "D1" smd circle
			(at -1.500124 0.750062)
			(size 0.2286 0.2286)
			(layers "F.Cu" "F.Mask" "F.Paste")
			(net "P12V_OCP_REG_1")
		)
		(pad "D2" smd circle
			(at -0.999998 0.750062)
			(size 0.2286 0.2286)
			(layers "F.Cu" "F.Mask" "F.Paste")
			(net "P12V_OCP_UV_1")
		)
		(pad "D3" smd circle
			(at -0.499872 0.750062)
			(size 0.2286 0.2286)
			(layers "F.Cu" "F.Mask" "F.Paste")
			(net "P12V_OCP_OV_1")
		)
		(pad "D4" smd circle
			(at 0 0.750062)
			(size 0.2286 0.2286)
			(layers "F.Cu" "F.Mask" "F.Paste")
			(net "P12V_OCP_SFF")
		)
		(pad "D5" smd circle
			(at 0.499872 0.750062)
			(size 0.2286 0.2286)
			(layers "F.Cu" "F.Mask" "F.Paste")
			(net "P12V_AUX")
		)
		(pad "D6" smd circle
			(at 0.999998 0.750062)
			(size 0.2286 0.2286)
			(layers "F.Cu" "F.Mask" "F.Paste")
			(net "P12V_OCP_SFF")
		)
		(pad "D7" smd circle
			(at 1.500124 0.750062)
			(size 0.2286 0.2286)
			(layers "F.Cu" "F.Mask" "F.Paste")
			(net "P12V_OCP_PWRGD_1")
		)
	)
	(footprint ""
		(layer "F.Cu")
		(at 64.83858 -54.22138 -90)
		(property "Reference" "C9051"
			(at 0 0 270)
			(layer "F.SilkS")
			(hide yes)
			(effects
				(font
					(size 1.27 1.27)
				)
			)
		)
		(property "Value" ""
			(at 0 0 270)
			(layer "F.Fab")
			(effects
				(font
					(size 1.27 1.27)
				)
			)
		)
		(duplicate_pad_numbers_are_jumpers no)
		(fp_line
			(start -0.7874 0.4064)
			(end -0.7874 -0.4064)
			(stroke
				(width 0.1524)
				(type default)
			)
			(layer "F.SilkS")
		)
		(fp_line
			(start 0.7874 0.4064)
			(end -0.7874 0.4064)
			(stroke
				(width 0.1524)
				(type default)
			)
			(layer "F.SilkS")
		)
		(fp_line
			(start -0.7874 -0.4064)
			(end 0.7874 -0.4064)
			(stroke
				(width 0.1524)
				(type default)
			)
			(layer "F.SilkS")
		)
		(fp_line
			(start 0.7874 -0.4064)
			(end 0.7874 0.4064)
			(stroke
				(width 0.1524)
				(type default)
			)
			(layer "F.SilkS")
		)
		(fp_line
			(start -0.67945 0.3048)
			(end -0.67945 -0.305054)
			(stroke
				(width 0.1)
				(type default)
			)
			(layer "F.Fab")
		)
		(fp_line
			(start -0.12065 0.3048)
			(end -0.67945 0.3048)
			(stroke
				(width 0.1)
				(type default)
			)
			(layer "F.Fab")
		)
		(fp_line
			(start 0.120396 0.3048)
			(end 0.120396 0.2794)
			(stroke
				(width 0.1)
				(type default)
			)
			(layer "F.Fab")
		)
		(fp_line
			(start 0.67945 0.3048)
			(end 0.120396 0.3048)
			(stroke
				(width 0.1)
				(type default)
			)
			(layer "F.Fab")
		)
		(fp_line
			(start -0.12065 0.2794)
			(end -0.12065 0.3048)
			(stroke
				(width 0.1)
				(type default)
			)
			(layer "F.Fab")
		)
		(fp_line
			(start 0.120396 0.2794)
			(end -0.12065 0.2794)
			(stroke
				(width 0.1)
				(type default)
			)
			(layer "F.Fab")
		)
		(fp_line
			(start -0.12065 -0.2794)
			(end 0.12065 -0.2794)
			(stroke
				(width 0.1)
				(type default)
			)
			(layer "F.Fab")
		)
		(fp_line
			(start 0.12065 -0.2794)
			(end 0.12065 -0.3048)
			(stroke
				(width 0.1)
				(type default)
			)
			(layer "F.Fab")
		)
		(fp_line
			(start 0.12065 -0.3048)
			(end 0.67945 -0.3048)
			(stroke
				(width 0.1)
				(type default)
			)
			(layer "F.Fab")
		)
		(fp_line
			(start 0.67945 -0.3048)
			(end 0.67945 0.3048)
			(stroke
				(width 0.1)
				(type default)
			)
			(layer "F.Fab")
		)
		(fp_line
			(start -0.67945 -0.305054)
			(end -0.12065 -0.305054)
			(stroke
				(width 0.1)
				(type default)
			)
			(layer "F.Fab")
		)
		(fp_line
			(start -0.12065 -0.305054)
			(end -0.12065 -0.2794)
			(stroke
				(width 0.1)
				(type default)
			)
			(layer "F.Fab")
		)
		(pad "1" smd circle
			(at -0.40005 0 270)
			(size 0 0)
			(layers "F.Cu" "F.Mask" "F.Paste")
			(net "P3V3_AUX")
		)
		(pad "2" smd circle
			(at 0.40005 0 270)
			(size 0 0)
			(layers "F.Cu" "F.Mask" "F.Paste")
			(net "GND")
		)
	)
	(footprint ""
		(layer "F.Cu")
		(at 299.767498 -14.48181 180)
		(property "Reference" "R4196"
			(at 0 0 180)
			(layer "F.SilkS")
			(hide yes)
			(effects
				(font
					(size 1.27 1.27)
				)
			)
		)
		(property "Value" ""
			(at 0 0 180)
			(layer "F.Fab")
			(effects
				(font
					(size 1.27 1.27)
				)
			)
		)
		(duplicate_pad_numbers_are_jumpers no)
		(fp_line
			(start 0.7874 0.4064)
			(end -0.7874 0.4064)
			(stroke
				(width 0.1524)
				(type default)
			)
			(layer "F.SilkS")
		)
		(fp_line
			(start 0.7874 -0.4064)
			(end 0.7874 0.4064)
			(stroke
				(width 0.1524)
				(type default)
			)
			(layer "F.SilkS")
		)
		(fp_line
			(start -0.7874 0.4064)
			(end -0.7874 -0.4064)
			(stroke
				(width 0.1524)
				(type default)
			)
			(layer "F.SilkS")
		)
		(fp_line
			(start -0.7874 -0.4064)
			(end 0.7874 -0.4064)
			(stroke
				(width 0.1524)
				(type default)
			)
			(layer "F.SilkS")
		)
		(fp_line
			(start 0.67945 0.3048)
			(end 0.120396 0.3048)
			(stroke
				(width 0.1)
				(type default)
			)
			(layer "F.Fab")
		)
		(fp_line
			(start 0.67945 -0.3048)
			(end 0.67945 0.3048)
			(stroke
				(width 0.1)
				(type default)
			)
			(layer "F.Fab")
		)
		(fp_line
			(start 0.12065 -0.2794)
			(end 0.12065 -0.3048)
			(stroke
				(width 0.1)
				(type default)
			)
			(layer "F.Fab")
		)
		(fp_line
			(start 0.12065 -0.3048)
			(end 0.67945 -0.3048)
			(stroke
				(width 0.1)
				(type default)
			)
			(layer "F.Fab")
		)
		(fp_line
			(start 0.120396 0.3048)
			(end 0.120396 0.2794)
			(stroke
				(width 0.1)
				(type default)
			)
			(layer "F.Fab")
		)
		(fp_line
			(start 0.120396 0.2794)
			(end -0.12065 0.2794)
			(stroke
				(width 0.1)
				(type default)
			)
			(layer "F.Fab")
		)
		(fp_line
			(start -0.12065 0.3048)
			(end -0.67945 0.3048)
			(stroke
				(width 0.1)
				(type default)
			)
			(layer "F.Fab")
		)
		(fp_line
			(start -0.12065 0.2794)
			(end -0.12065 0.3048)
			(stroke
				(width 0.1)
				(type default)
			)
			(layer "F.Fab")
		)
		(fp_line
			(start -0.12065 -0.2794)
			(end 0.12065 -0.2794)
			(stroke
				(width 0.1)
				(type default)
			)
			(layer "F.Fab")
		)
		(fp_line
			(start -0.12065 -0.305054)
			(end -0.12065 -0.2794)
			(stroke
				(width 0.1)
				(type default)
			)
			(layer "F.Fab")
		)
		(fp_line
			(start -0.67945 0.3048)
			(end -0.67945 -0.305054)
			(stroke
				(width 0.1)
				(type default)
			)
			(layer "F.Fab")
		)
		(fp_line
			(start -0.67945 -0.305054)
			(end -0.12065 -0.305054)
			(stroke
				(width 0.1)
				(type default)
			)
			(layer "F.Fab")
		)
		(pad "1" smd circle
			(at -0.40005 0 180)
			(size 0 0)
			(layers "F.Cu" "F.Mask" "F.Paste")
			(net "P3V3_AUX")
		)
		(pad "2" smd circle
			(at 0.40005 0 180)
			(size 0 0)
			(layers "F.Cu" "F.Mask" "F.Paste")
			(net "U271_1_ADD1")
		)
	)
	(footprint ""
		(layer "F.Cu")
		(at 123.704096 -373.03583 -90)
		(property "Reference" "C1531"
			(at 0 0 270)
			(layer "F.SilkS")
			(hide yes)
			(effects
				(font
					(size 1.27 1.27)
				)
			)
		)
		(property "Value" ""
			(at 0 0 270)
			(layer "F.Fab")
			(effects
				(font
					(size 1.27 1.27)
				)
			)
		)
		(duplicate_pad_numbers_are_jumpers no)
		(fp_line
			(start -0.299974 0.150114)
			(end -0.299974 -0.150114)
			(stroke
				(width 0.1)
				(type default)
			)
			(layer "F.Fab")
		)
		(fp_line
			(start 0.299974 0.150114)
			(end -0.299974 0.150114)
			(stroke
				(width 0.1)
				(type default)
			)
			(layer "F.Fab")
		)
		(fp_line
			(start -0.299974 -0.150114)
			(end 0.299974 -0.150114)
			(stroke
				(width 0.1)
				(type default)
			)
			(layer "F.Fab")
		)
		(fp_line
			(start 0.299974 -0.150114)
			(end 0.299974 0.150114)
			(stroke
				(width 0.1)
				(type default)
			)
			(layer "F.Fab")
		)
		(pad "1" smd rect
			(at -0.2667 0 270)
			(size 0.3048 0.381)
			(layers "F.Cu" "F.Mask" "F.Paste")
			(net "P5E_CPU1_P3_TX_C_DP<8>")
		)
		(pad "2" smd rect
			(at 0.2667 0 270)
			(size 0.3048 0.381)
			(layers "F.Cu" "F.Mask" "F.Paste")
			(net "P5E_CPU1_P3_TX_DP<8>")
		)
	)
	(footprint ""
		(layer "F.Cu")
		(at 256.47269 -40.498522 90)
		(property "Reference" "PC2214"
			(at 0 0 90)
			(layer "F.SilkS")
			(hide yes)
			(effects
				(font
					(size 1.27 1.27)
				)
			)
		)
		(property "Value" ""
			(at 0 0 90)
			(layer "F.Fab")
			(effects
				(font
					(size 1.27 1.27)
				)
			)
		)
		(duplicate_pad_numbers_are_jumpers no)
		(fp_line
			(start 0.7874 -0.4064)
			(end 0.7874 0.4064)
			(stroke
				(width 0.1524)
				(type default)
			)
			(layer "F.SilkS")
		)
		(fp_line
			(start -0.7874 -0.4064)
			(end 0.7874 -0.4064)
			(stroke
				(width 0.1524)
				(type default)
			)
			(layer "F.SilkS")
		)
		(fp_line
			(start 0.7874 0.4064)
			(end -0.7874 0.4064)
			(stroke
				(width 0.1524)
				(type default)
			)
			(layer "F.SilkS")
		)
		(fp_line
			(start -0.7874 0.4064)
			(end -0.7874 -0.4064)
			(stroke
				(width 0.1524)
				(type default)
			)
			(layer "F.SilkS")
		)
		(fp_line
			(start -0.12065 -0.305054)
			(end -0.12065 -0.2794)
			(stroke
				(width 0.1)
				(type default)
			)
			(layer "F.Fab")
		)
		(fp_line
			(start -0.67945 -0.305054)
			(end -0.12065 -0.305054)
			(stroke
				(width 0.1)
				(type default)
			)
			(layer "F.Fab")
		)
		(fp_line
			(start 0.67945 -0.3048)
			(end 0.67945 0.3048)
			(stroke
				(width 0.1)
				(type default)
			)
			(layer "F.Fab")
		)
		(fp_line
			(start 0.12065 -0.3048)
			(end 0.67945 -0.3048)
			(stroke
				(width 0.1)
				(type default)
			)
			(layer "F.Fab")
		)
		(fp_line
			(start 0.12065 -0.2794)
			(end 0.12065 -0.3048)
			(stroke
				(width 0.1)
				(type default)
			)
			(layer "F.Fab")
		)
		(fp_line
			(start -0.12065 -0.2794)
			(end 0.12065 -0.2794)
			(stroke
				(width 0.1)
				(type default)
			)
			(layer "F.Fab")
		)
		(fp_line
			(start 0.120396 0.2794)
			(end -0.12065 0.2794)
			(stroke
				(width 0.1)
				(type default)
			)
			(layer "F.Fab")
		)
		(fp_line
			(start -0.12065 0.2794)
			(end -0.12065 0.3048)
			(stroke
				(width 0.1)
				(type default)
			)
			(layer "F.Fab")
		)
		(fp_line
			(start 0.67945 0.3048)
			(end 0.120396 0.3048)
			(stroke
				(width 0.1)
				(type default)
			)
			(layer "F.Fab")
		)
		(fp_line
			(start 0.120396 0.3048)
			(end 0.120396 0.2794)
			(stroke
				(width 0.1)
				(type default)
			)
			(layer "F.Fab")
		)
		(fp_line
			(start -0.12065 0.3048)
			(end -0.67945 0.3048)
			(stroke
				(width 0.1)
				(type default)
			)
			(layer "F.Fab")
		)
		(fp_line
			(start -0.67945 0.3048)
			(end -0.67945 -0.305054)
			(stroke
				(width 0.1)
				(type default)
			)
			(layer "F.Fab")
		)
		(pad "1" smd circle
			(at -0.40005 0 90)
			(size 0 0)
			(layers "F.Cu" "F.Mask" "F.Paste")
			(net "P12V_E1S_0")
		)
		(pad "2" smd circle
			(at 0.40005 0 90)
			(size 0 0)
			(layers "F.Cu" "F.Mask" "F.Paste")
			(net "P12V_E1S_GATE_0")
		)
	)
	(footprint ""
		(layer "F.Cu")
		(at 399.171668 -396.412974 90)
		(property "Reference" "R634"
			(at 0 0 90)
			(layer "F.SilkS")
			(hide yes)
			(effects
				(font
					(size 1.27 1.27)
				)
			)
		)
		(property "Value" ""
			(at 0 0 90)
			(layer "F.Fab")
			(effects
				(font
					(size 1.27 1.27)
				)
			)
		)
		(duplicate_pad_numbers_are_jumpers no)
		(fp_line
			(start 0.32512 -0.175006)
			(end 0.32512 0.175006)
			(stroke
				(width 0.1)
				(type default)
			)
			(layer "F.Fab")
		)
		(fp_line
			(start -0.32512 -0.175006)
			(end 0.32512 -0.175006)
			(stroke
				(width 0.1)
				(type default)
			)
			(layer "F.Fab")
		)
		(fp_line
			(start 0.32512 0.175006)
			(end -0.32512 0.175006)
			(stroke
				(width 0.1)
				(type default)
			)
			(layer "F.Fab")
		)
		(fp_line
			(start -0.32512 0.175006)
			(end -0.32512 -0.175006)
			(stroke
				(width 0.1)
				(type default)
			)
			(layer "F.Fab")
		)
		(pad "1" smd rect
			(at -0.2667 0 90)
			(size 0.3048 0.381)
			(layers "F.Cu" "F.Mask" "F.Paste")
			(net "CLK_100M_RETIMER_CPU0_P2_DP")
		)
		(pad "2" smd rect
			(at 0.2667 0 270)
			(size 0.3048 0.381)
			(layers "F.Cu" "F.Mask" "F.Paste")
			(net "GND")
		)
	)
)
